# S9S_MB_2U (Grand Teton) — schematic netlist excerpt (pin names and nets, part order shuffled) for the footprints in the layout excerpt that follows; sources: Cadence DE-HDL packaged netlist, KiCad conversion of 03242023_DA0F0TMBIJ0_F0T_Motherboard_J_brd_V01_OCP.brd

J2  SCONN288_ADR50017P087CC  SCONN288_ADR50017-P087CC IO  pkg DDR288S_1-1VXB  page 83
  VIN_BULK0  = P12V_S3_AUX_CPU0_NVDIMM
  RFU0  = TP_CHA_CPU0_DIMM2_FRU_0
  VIN_MGMT  = P3V3_AUX
  HSCL  = I3C_SPD_DDRABCD_CPU0_LVC1_SCL_1
  HSDA  = I3C_SPD_DDRABCD_CPU0_LVC1_SDA
  VSS0  = GND
  DQ0_A  = M_A_CPU0_SA_DQ<0>
  VSS1  = GND
  DQ1_A  = M_A_CPU0_SA_DQ<1>
  VSS2  = GND
  DQS0_A_T  = M_A_CPU0_SA_DQS_DP<0>
  DQS0_A_C  = M_A_CPU0_SA_DQS_DN<0>
  VSS3  = GND
  DQ4_A  = M_A_CPU0_SA_DQ<4>
  VSS4  = GND
  DQ5_A  = M_A_CPU0_SA_DQ<5>
  VSS5  = GND
  DQ8_A  = M_A_CPU0_SA_DQ<8>
  VSS6  = GND
  DQ9_A  = M_A_CPU0_SA_DQ<9>
  VSS7  = GND
  DQS1_A_T  = M_A_CPU0_SA_DQS_DP<1>
  DQS1_A_C  = M_A_CPU0_SA_DQS_DN<1>
  VSS8  = GND
  DQ12_A  = M_A_CPU0_SA_DQ<12>
  VSS9  = GND
  DQ13_A  = M_A_CPU0_SA_DQ<13>
  VSS10  = GND
  DQ16_A  = M_A_CPU0_SA_DQ<16>
  VSS11  = GND
  DQ17_A  = M_A_CPU0_SA_DQ<17>
  VSS12  = GND
  DQS2_A_T  = M_A_CPU0_SA_DQS_DP<2>
  DQS2_A_C  = M_A_CPU0_SA_DQS_DN<2>
  VSS13  = GND
  DQ20_A  = M_A_CPU0_SA_DQ<20>
  VSS14  = GND
  DQ21_A  = M_A_CPU0_SA_DQ<21>
  VSS15  = GND
  DQ24_A  = M_A_CPU0_SA_DQ<24>
  VSS16  = GND
  DQ25_A  = M_A_CPU0_SA_DQ<25>
  VSS17  = GND
  DQS3_A_T  = M_A_CPU0_SA_DQS_DP<3>
  DQS3_A_C  = M_A_CPU0_SA_DQS_DN<3>
  VSS18  = GND
  DQ28_A  = M_A_CPU0_SA_DQ<28>
  VSS19  = GND
  DQ29_A  = M_A_CPU0_SA_DQ<29>
  VSS20  = GND
  CB0_A  = M_A_CPU0_SA_CB<0>
  VSS21  = GND
  CB1_A  = M_A_CPU0_SA_CB<1>
  VSS22  = GND
  DQS4_A_T  = M_A_CPU0_SA_DQS_DP<4>
  DQS4_A_C  = M_A_CPU0_SA_DQS_DN<4>
  VSS23  = GND
  CB4_A  = M_A_CPU0_SA_CB<4>
  VSS24  = GND
  CB5_A  = M_A_CPU0_SA_CB<5>
  VSS25  = GND
  ALERT_N  = M_A_CPU0_ALERT_N
  VSS26  = GND
  CS0_A_N  = M_A_CPU0_SA_CS_N<2>
  VSS27  = GND
  CA0_A  = M_A_CPU0_SA_CA<0>
  VSS28  = GND
  CA2_A  = M_A_CPU0_SA_CA<2>
  VSS29  = GND
  CA4_A  = M_A_CPU0_SA_CA<4>
  VSS30  = GND
  CA6_A  = M_A_CPU0_SA_CA<6>
  VSS31  = GND
  PAR_A  = M_A_CPU0_SA_PAR
  VSS32  = GND
  CA0_B  = M_A_CPU0_SB_CA<0>
  VSS33  = GND
  CA2_B  = M_A_CPU0_SB_CA<2>
  VSS34  = GND
  CA4_B  = M_A_CPU0_SB_CA<4>
  VSS35  = GND
  CA6_B  = M_A_CPU0_SB_CA<6>
  VSS36  = GND
  CS0_B_N  = M_A_CPU0_SB_CS_N<2>
  VSS37  = GND
  \lbd||rsp_a_n\  = M_A_CPU0_SA_RSP<1>
  \lbs||rsp_b_n\  = M_A_CPU0_SB_RSP<1>
  VSS38  = GND
  CB4_B  = M_A_CPU0_SB_CB<4>
  VSS39  = GND
  CB5_B  = M_A_CPU0_SB_CB<5>
  VSS40  = GND
  \dqs9_b_t||tdqs9_b_t||dbi4_b_n\  = M_A_CPU0_SB_DQS_DP<9>
  \dqs9_b_c||tdqs9_b_c\  = M_A_CPU0_SB_DQS_DN<9>
  VSS41  = GND
  CB0_B  = M_A_CPU0_SB_CB<0>
  VSS42  = GND
  CB1_B  = M_A_CPU0_SB_CB<1>
  VSS43  = GND
  DQ0_B  = M_A_CPU0_SB_DQ<0>
  VSS44  = GND
  DQ1_B  = M_A_CPU0_SB_DQ<1>
  VSS45  = GND
  DQS0_B_T  = M_A_CPU0_SB_DQS_DP<0>
  DQS0_B_C  = M_A_CPU0_SB_DQS_DN<0>
  VSS46  = GND
  DQ4_B  = M_A_CPU0_SB_DQ<4>
  VSS47  = GND
  DQ5_B  = M_A_CPU0_SB_DQ<5>
  VSS48  = GND
  DQ8_B  = M_A_CPU0_SB_DQ<8>
  VSS49  = GND
  DQ9_B  = M_A_CPU0_SB_DQ<9>
  VSS50  = GND
  DQS1_B_T  = M_A_CPU0_SB_DQS_DP<1>
  DQS1_B_C  = M_A_CPU0_SB_DQS_DN<1>
  VSS51  = GND
  DQ12_B  = M_A_CPU0_SB_DQ<12>
  VSS52  = GND
  DQ13_B  = M_A_CPU0_SB_DQ<13>
  VSS53  = GND
  DQ16_B  = M_A_CPU0_SB_DQ<16>
  VSS54  = GND
  DQ17_B  = M_A_CPU0_SB_DQ<17>
  VSS55  = GND
  DQS2_B_T  = M_A_CPU0_SB_DQS_DP<2>
  DQS2_B_C  = M_A_CPU0_SB_DQS_DN<2>
  VSS56  = GND
  DQ20_B  = M_A_CPU0_SB_DQ<20>
  VSS57  = GND
  DQ21_B  = M_A_CPU0_SB_DQ<21>
  VSS58  = GND
  DQ24_B  = M_A_CPU0_SB_DQ<24>
  VSS59  = GND
  DQ25_B  = M_A_CPU0_SB_DQ<25>
  VSS60  = GND
  DQS3_B_T  = M_A_CPU0_SB_DQS_DP<3>
  DQS3_B_C  = M_A_CPU0_SB_DQS_DN<3>
  VSS61  = GND
  DQ28_B  = M_A_CPU0_SB_DQ<28>
  VSS62  = GND
  DQ29_B  = M_A_CPU0_SB_DQ<29>
  VSS63  = GND
  RFU1  = TP_CHA_CPU0_DIMM2_FRU_1
  VIN_BULK1  = P12V_S3_AUX_CPU0_NVDIMM
  VIN_BULK2  = P12V_S3_AUX_CPU0_NVDIMM
  \pwr_good||fail_n\  = PWRGD_CHA_CPU0_DIMM2
  HSA  = PD_CHA_CPU0_DIMM2_SAA
  RFU2  = TP_CHA_CPU0_DIMM2_FRU_2
  RFU3  = TP_CHA_CPU0_DIMM2_FRU_3
  VSS64  = GND
  DQ2_A  = M_A_CPU0_SA_DQ<2>
  VSS65  = GND
  DQ3_A  = M_A_CPU0_SA_DQ<3>
  VSS66  = GND
  \dqs5_a_c||tdqs5_a_c||dqs5_a_t||tdqs5_a_t\  = M_A_CPU0_SA_DQS_DN<5>
  \dqs5_a_t||tdqs5_a_t\  = M_A_CPU0_SA_DQS_DP<5>
  VSS67  = GND
  DQ6_A  = M_A_CPU0_SA_DQ<6>
  VSS68  = GND
  DQ7_A  = M_A_CPU0_SA_DQ<7>
  VSS69  = GND
  DQ10_A  = M_A_CPU0_SA_DQ<10>
  VSS70  = GND
  DQ11_A  = M_A_CPU0_SA_DQ<11>
  VSS71  = GND
  \dqs6_a_c||tdqs6_a_c||dqs6_a_t||tdqs6_a_t\  = M_A_CPU0_SA_DQS_DN<6>
  \dqs6_a_t||tdqs6_a_t\  = M_A_CPU0_SA_DQS_DP<6>
  VSS72  = GND
  DQ14_A  = M_A_CPU0_SA_DQ<14>
  VSS73  = GND
  DQ15_A  = M_A_CPU0_SA_DQ<15>
  VSS74  = GND
  DQ18_A  = M_A_CPU0_SA_DQ<18>
  VSS75  = GND
  DQ19_A  = M_A_CPU0_SA_DQ<19>
  VSS76  = GND
  \dqs7_a_c||tdqs7_a_c\  = M_A_CPU0_SA_DQS_DN<7>
  \dqs7_a_t||tdqs7_a_t\  = M_A_CPU0_SA_DQS_DP<7>
  VSS77  = GND
  DQ22_A  = M_A_CPU0_SA_DQ<22>
  VSS78  = GND
  DQ23_A  = M_A_CPU0_SA_DQ<23>
  VSS79  = GND
  DQ26_A  = M_A_CPU0_SA_DQ<26>
  VSS80  = GND
  DQ27_A  = M_A_CPU0_SA_DQ<27>
  VSS81  = GND
  \dqs8_a_c||tdqs8_a_c\  = M_A_CPU0_SA_DQS_DN<8>
  \dqs8_a_t||tdqs8_a_t\  = M_A_CPU0_SA_DQS_DP<8>
  VSS82  = GND
  DQ30_A  = M_A_CPU0_SA_DQ<30>
  VSS83  = GND
  DQ31_A  = M_A_CPU0_SA_DQ<31>
  VSS84  = GND
  CB2_A  = M_A_CPU0_SA_CB<2>
  VSS85  = GND
  CB3_A  = M_A_CPU0_SA_CB<3>
  VSS86  = GND
  \dqs9_a_c||tdqs9_a_c\  = M_A_CPU0_SA_DQS_DN<9>
  \dqs9_a_t||tdqs9_a_t\  = M_A_CPU0_SA_DQS_DP<9>
  VSS87  = GND
  CB6_A  = M_A_CPU0_SA_CB<6>
  VSS88  = GND
  CB7_A  = M_A_CPU0_SA_CB<7>
  VSS89  = GND
  RESET_N  = RST_M_AB_CPU0_FPGA_N
  VSS90  = GND
  CS1_A_N  = M_A_CPU0_SA_CS_N<3>
  VSS91  = GND
  CA1_A  = M_A_CPU0_SA_CA<1>
  VSS92  = GND
  CA3_A  = M_A_CPU0_SA_CA<3>
  VSS93  = GND
  CA5_A  = M_A_CPU0_SA_CA<5>
  VSS94  = GND
  CK_T  = M_A_CPU0_CLK_DP<1>
  CK_C  = M_A_CPU0_CLK_DN<1>
  VSS95  = GND
  RFU4  = TP_CHA_CPU0_DIMM2_FRU_4
  CA1_B  = M_A_CPU0_SB_CA<1>
  VSS96  = GND
  CA3_B  = M_A_CPU0_SB_CA<3>
  VSS97  = GND
  CA5_B  = M_A_CPU0_SB_CA<5>
  VSS98  = GND
  PAR_B  = M_A_CPU0_SB_PAR
  VSS99  = GND
  CS1_B_N  = M_A_CPU0_SB_CS_N<3>
  VSS100  = GND
  RFU5  = TP_CHA_CPU0_DIMM2_FRU_5
  RFU6  = TP_CHA_CPU0_DIMM2_FRU_6
  VSS101  = GND
  CB6_B  = M_A_CPU0_SB_CB<6>
  VSS102  = GND
  CB7_B  = M_A_CPU0_SB_CB<7>
  VSS103  = GND
  DQS4_B_C  = M_A_CPU0_SB_DQS_DN<4>
  DQS4_B_T  = M_A_CPU0_SB_DQS_DP<4>
  VSS104  = GND
  CB2_B  = M_A_CPU0_SB_CB<2>
  VSS105  = GND
  CB3_B  = M_A_CPU0_SB_CB<3>
  VSS106  = GND
  DQ2_B  = M_A_CPU0_SB_DQ<2>
  VSS107  = GND
  DQ3_B  = M_A_CPU0_SB_DQ<3>
  VSS108  = GND
  \dqs5_b_c||tdqs5_b_c\  = M_A_CPU0_SB_DQS_DN<5>
  \dqs5_b_t||tdqs5_b_t\  = M_A_CPU0_SB_DQS_DP<5>
  VSS109  = GND
  DQ6_B  = M_A_CPU0_SB_DQ<6>
  VSS110  = GND
  DQ7_B  = M_A_CPU0_SB_DQ<7>
  VSS111  = GND
  DQ10_B  = M_A_CPU0_SB_DQ<10>
  VSS112  = GND
  DQ11_B  = M_A_CPU0_SB_DQ<11>
  VSS113  = GND
  \dqs6_b_c||tdqs6_b_c\  = M_A_CPU0_SB_DQS_DN<6>
  \dqs6_b_t||tdqs6_b_t\  = M_A_CPU0_SB_DQS_DP<6>
  VSS114  = GND
  DQ14_B  = M_A_CPU0_SB_DQ<14>
  VSS115  = GND
  DQ15_B  = M_A_CPU0_SB_DQ<15>
  VSS116  = GND
  DQ18_B  = M_A_CPU0_SB_DQ<18>
  VSS117  = GND
  DQ19_B  = M_A_CPU0_SB_DQ<19>
  VSS118  = GND
  \dqs7_b_c||tdqs7_b_c\  = M_A_CPU0_SB_DQS_DN<7>
  \dqs7_b_t||tdqs7_b_t\  = M_A_CPU0_SB_DQS_DP<7>
  VSS119  = GND
  DQ22_B  = M_A_CPU0_SB_DQ<22>
  VSS120  = GND
  DQ23_B  = M_A_CPU0_SB_DQ<23>
  VSS121  = GND
  DQ26_B  = M_A_CPU0_SB_DQ<26>
  VSS122  = GND
  DQ27_B  = M_A_CPU0_SB_DQ<27>
  VSS123  = GND
  \dqs8_b_c||tdqs8_b_c\  = M_A_CPU0_SB_DQS_DN<8>
  \dqs8_b_t||tdqs8_b_t\  = M_A_CPU0_SB_DQS_DP<8>
  VSS124  = GND
  DQ30_B  = M_A_CPU0_SB_DQ<30>
  VSS125  = GND
  DQ31_B  = M_A_CPU0_SB_DQ<31>
  VSS126  = GND
  G1  = GND
  G2  = GND
  G3  = GND

(kicad_pcb
	(version 20260206)
	(generator "pcbnew")
	(generator_version "10.0")
	(general
		(thickness 1.6)
		(legacy_teardrops no)
	)
	(paper "A4")
	(title_block
		(title "03242023_DA0F0TMBIJ0_F0T_Motherboard_J_brd_V01_OCP.brd")
		(comment 1 "Grand Teton / footprint 2856 of 6105 (J2), pads 1-45 of 291")
	)
	(layers
		(0 "F.Cu" signal "TOP")
		(4 "In1.Cu" signal "GND")
		(6 "In2.Cu" signal "IN1")
		(8 "In3.Cu" signal "GND1")
		(10 "In4.Cu" signal "IN2")
		(12 "In5.Cu" signal "GND2")
		(14 "In6.Cu" signal "IN3")
		(16 "In7.Cu" signal "GND3")
		(18 "In8.Cu" signal "VCC")
		(20 "In9.Cu" signal "VCC1")
		(22 "In10.Cu" signal "GND4")
		(24 "In11.Cu" signal "IN4")
		(26 "In12.Cu" signal "GND5")
		(28 "In13.Cu" signal "IN5")
		(30 "In14.Cu" signal "GND6")
		(32 "In15.Cu" signal "IN6")
		(34 "In16.Cu" signal "GND7")
		(2 "B.Cu" signal "BOTTOM")
		(9 "F.Adhes" user "F.Adhesive")
		(11 "B.Adhes" user "B.Adhesive")
		(13 "F.Paste" user "Package Geometry/Pastemask Top")
		(15 "B.Paste" user "Package Geometry/Pastemask Bottom")
		(5 "F.SilkS" user "Ref Des/Silkscreen Top")
		(7 "B.SilkS" user "Ref Des/Silkscreen Bottom")
		(1 "F.Mask" user "Board Geometry/Soldermask Top")
		(3 "B.Mask" user "Board Geometry/Soldermask Bottom")
		(17 "Dwgs.User" user "User.Drawings")
		(19 "Cmts.User" user "User.Comments")
		(21 "Eco1.User" user "User.Eco1")
		(23 "Eco2.User" user "User.Eco2")
		(25 "Edge.Cuts" user "Board Geometry/Outline")
		(27 "Margin" user)
		(31 "F.CrtYd" user "Package Geometry/Place Bound Top")
		(29 "B.CrtYd" user "Package Geometry/Place Bound Bottom")
		(35 "F.Fab" user "Ref Des/Assembly Top")
		(33 "B.Fab" user "Ref Des/Assembly Bottom")
	)
	(footprint ""
		(layer "F.Cu")
		(at 310.937148 -258.091686)
		(property "Reference" "J2"
			(at -3.683 -81.702148 0)
			(unlocked yes)
			(layer "F.SilkS")
			(effects
				(font
					(size 0.7874 0.5842)
					(thickness 0.1524)
				)
				(justify left)
			)
		)
		(property "Value" ""
			(at 0 0 0)
			(layer "F.Fab")
			(effects
				(font
					(size 1.27 1.27)
				)
			)
		)
		(duplicate_pad_numbers_are_jumpers no)
		(pad "1" smd rect
			(at -2.050034 -63.324994 270)
			(size 0.519938 1.4986)
			(layers "F.Cu" "F.Mask" "F.Paste")
			(net "P12V_S3_AUX_CPU0_NVDIMM")
		)
		(pad "2" smd rect
			(at -2.050034 -62.47511 270)
			(size 0.519938 1.4986)
			(layers "F.Cu" "F.Mask" "F.Paste")
			(net "TP_CHA_CPU0_DIMM2_FRU_0")
		)
		(pad "3" smd rect
			(at -2.050034 -61.624972 270)
			(size 0.519938 1.4986)
			(layers "F.Cu" "F.Mask" "F.Paste")
			(net "P3V3_AUX")
		)
		(pad "4" smd rect
			(at -2.050034 -60.775088 270)
			(size 0.519938 1.4986)
			(layers "F.Cu" "F.Mask" "F.Paste")
			(net "I3C_SPD_DDRABCD_CPU0_LVC1_SCL_1")
		)
		(pad "5" smd rect
			(at -2.050034 -59.92495 270)
			(size 0.519938 1.4986)
			(layers "F.Cu" "F.Mask" "F.Paste")
			(net "I3C_SPD_DDRABCD_CPU0_LVC1_SDA")
		)
		(pad "6" smd rect
			(at -2.050034 -59.075066 270)
			(size 0.519938 1.4986)
			(layers "F.Cu" "F.Mask" "F.Paste")
			(net "GND")
		)
		(pad "7" smd rect
			(at -2.050034 -58.224928 270)
			(size 0.519938 1.4986)
			(layers "F.Cu" "F.Mask" "F.Paste")
			(net "M_A_CPU0_SA_DQ<0>")
		)
		(pad "8" smd rect
			(at -2.050034 -57.375044 270)
			(size 0.519938 1.4986)
			(layers "F.Cu" "F.Mask" "F.Paste")
			(net "GND")
		)
		(pad "9" smd rect
			(at -2.050034 -56.524906 270)
			(size 0.519938 1.4986)
			(layers "F.Cu" "F.Mask" "F.Paste")
			(net "M_A_CPU0_SA_DQ<1>")
		)
		(pad "10" smd rect
			(at -2.050034 -55.675022 270)
			(size 0.519938 1.4986)
			(layers "F.Cu" "F.Mask" "F.Paste")
			(net "GND")
		)
		(pad "11" smd rect
			(at -2.050034 -54.824884 270)
			(size 0.519938 1.4986)
			(layers "F.Cu" "F.Mask" "F.Paste")
			(net "M_A_CPU0_SA_DQS_DP<0>")
		)
		(pad "12" smd rect
			(at -2.050034 -53.975 270)
			(size 0.519938 1.4986)
			(layers "F.Cu" "F.Mask" "F.Paste")
			(net "M_A_CPU0_SA_DQS_DN<0>")
		)
		(pad "13" smd rect
			(at -2.050034 -53.125116 270)
			(size 0.519938 1.4986)
			(layers "F.Cu" "F.Mask" "F.Paste")
			(net "GND")
		)
		(pad "14" smd rect
			(at -2.050034 -52.274978 270)
			(size 0.519938 1.4986)
			(layers "F.Cu" "F.Mask" "F.Paste")
			(net "M_A_CPU0_SA_DQ<4>")
		)
		(pad "15" smd rect
			(at -2.050034 -51.425094 270)
			(size 0.519938 1.4986)
			(layers "F.Cu" "F.Mask" "F.Paste")
			(net "GND")
		)
		(pad "16" smd rect
			(at -2.050034 -50.574956 270)
			(size 0.519938 1.4986)
			(layers "F.Cu" "F.Mask" "F.Paste")
			(net "M_A_CPU0_SA_DQ<5>")
		)
		(pad "17" smd rect
			(at -2.050034 -49.725072 270)
			(size 0.519938 1.4986)
			(layers "F.Cu" "F.Mask" "F.Paste")
			(net "GND")
		)
		(pad "18" smd rect
			(at -2.050034 -48.874934 270)
			(size 0.519938 1.4986)
			(layers "F.Cu" "F.Mask" "F.Paste")
			(net "M_A_CPU0_SA_DQ<8>")
		)
		(pad "19" smd rect
			(at -2.050034 -48.02505 270)
			(size 0.519938 1.4986)
			(layers "F.Cu" "F.Mask" "F.Paste")
			(net "GND")
		)
		(pad "20" smd rect
			(at -2.050034 -47.174912 270)
			(size 0.519938 1.4986)
			(layers "F.Cu" "F.Mask" "F.Paste")
			(net "M_A_CPU0_SA_DQ<9>")
		)
		(pad "21" smd rect
			(at -2.050034 -46.325028 270)
			(size 0.519938 1.4986)
			(layers "F.Cu" "F.Mask" "F.Paste")
			(net "GND")
		)
		(pad "22" smd rect
			(at -2.050034 -45.47489 270)
			(size 0.519938 1.4986)
			(layers "F.Cu" "F.Mask" "F.Paste")
			(net "M_A_CPU0_SA_DQS_DP<1>")
		)
		(pad "23" smd rect
			(at -2.050034 -44.625006 270)
			(size 0.519938 1.4986)
			(layers "F.Cu" "F.Mask" "F.Paste")
			(net "M_A_CPU0_SA_DQS_DN<1>")
		)
		(pad "24" smd rect
			(at -2.050034 -43.775122 270)
			(size 0.519938 1.4986)
			(layers "F.Cu" "F.Mask" "F.Paste")
			(net "GND")
		)
		(pad "25" smd rect
			(at -2.050034 -42.924984 270)
			(size 0.519938 1.4986)
			(layers "F.Cu" "F.Mask" "F.Paste")
			(net "M_A_CPU0_SA_DQ<12>")
		)
		(pad "26" smd rect
			(at -2.050034 -42.0751 270)
			(size 0.519938 1.4986)
			(layers "F.Cu" "F.Mask" "F.Paste")
			(net "GND")
		)
		(pad "27" smd rect
			(at -2.050034 -41.224962 270)
			(size 0.519938 1.4986)
			(layers "F.Cu" "F.Mask" "F.Paste")
			(net "M_A_CPU0_SA_DQ<13>")
		)
		(pad "28" smd rect
			(at -2.050034 -40.375078 270)
			(size 0.519938 1.4986)
			(layers "F.Cu" "F.Mask" "F.Paste")
			(net "GND")
		)
		(pad "29" smd rect
			(at -2.050034 -39.52494 270)
			(size 0.519938 1.4986)
			(layers "F.Cu" "F.Mask" "F.Paste")
			(net "M_A_CPU0_SA_DQ<16>")
		)
		(pad "30" smd rect
			(at -2.050034 -38.675056 270)
			(size 0.519938 1.4986)
			(layers "F.Cu" "F.Mask" "F.Paste")
			(net "GND")
		)
		(pad "31" smd rect
			(at -2.050034 -37.824918 270)
			(size 0.519938 1.4986)
			(layers "F.Cu" "F.Mask" "F.Paste")
			(net "M_A_CPU0_SA_DQ<17>")
		)
		(pad "32" smd rect
			(at -2.050034 -36.975034 270)
			(size 0.519938 1.4986)
			(layers "F.Cu" "F.Mask" "F.Paste")
			(net "GND")
		)
		(pad "33" smd rect
			(at -2.050034 -36.124896 270)
			(size 0.519938 1.4986)
			(layers "F.Cu" "F.Mask" "F.Paste")
			(net "M_A_CPU0_SA_DQS_DP<2>")
		)
		(pad "34" smd rect
			(at -2.050034 -35.275012 270)
			(size 0.519938 1.4986)
			(layers "F.Cu" "F.Mask" "F.Paste")
			(net "M_A_CPU0_SA_DQS_DN<2>")
		)
		(pad "35" smd rect
			(at -2.050034 -34.425128 270)
			(size 0.519938 1.4986)
			(layers "F.Cu" "F.Mask" "F.Paste")
			(net "GND")
		)
		(pad "36" smd rect
			(at -2.050034 -33.57499 270)
			(size 0.519938 1.4986)
			(layers "F.Cu" "F.Mask" "F.Paste")
			(net "M_A_CPU0_SA_DQ<20>")
		)
		(pad "37" smd rect
			(at -2.050034 -32.725106 270)
			(size 0.519938 1.4986)
			(layers "F.Cu" "F.Mask" "F.Paste")
			(net "GND")
		)
		(pad "38" smd rect
			(at -2.050034 -31.874968 270)
			(size 0.519938 1.4986)
			(layers "F.Cu" "F.Mask" "F.Paste")
			(net "M_A_CPU0_SA_DQ<21>")
		)
		(pad "39" smd rect
			(at -2.050034 -31.025084 270)
			(size 0.519938 1.4986)
			(layers "F.Cu" "F.Mask" "F.Paste")
			(net "GND")
		)
		(pad "40" smd rect
			(at -2.050034 -30.174946 270)
			(size 0.519938 1.4986)
			(layers "F.Cu" "F.Mask" "F.Paste")
			(net "M_A_CPU0_SA_DQ<24>")
		)
		(pad "41" smd rect
			(at -2.050034 -29.325062 270)
			(size 0.519938 1.4986)
			(layers "F.Cu" "F.Mask" "F.Paste")
			(net "GND")
		)
		(pad "42" smd rect
			(at -2.050034 -28.474924 270)
			(size 0.519938 1.4986)
			(layers "F.Cu" "F.Mask" "F.Paste")
			(net "M_A_CPU0_SA_DQ<25>")
		)
		(pad "43" smd rect
			(at -2.050034 -27.62504 270)
			(size 0.519938 1.4986)
			(layers "F.Cu" "F.Mask" "F.Paste")
			(net "GND")
		)
		(pad "44" smd rect
			(at -2.050034 -26.774902 270)
			(size 0.519938 1.4986)
			(layers "F.Cu" "F.Mask" "F.Paste")
			(net "M_A_CPU0_SA_DQS_DP<3>")
		)
		(pad "45" smd rect
			(at -2.050034 -25.925018 270)
			(size 0.519938 1.4986)
			(layers "F.Cu" "F.Mask" "F.Paste")
			(net "M_A_CPU0_SA_DQS_DN<3>")
		)
	)
)
